G04*
G04 #@! TF.GenerationSoftware,Altium Limited,Altium Designer,22.4.2 (48)*
G04*
G04 Layer_Color=8421504*
%FSLAX25Y25*%
%MOIN*%
G70*
G04*
G04 #@! TF.SameCoordinates,B69760C6-9901-4916-8BAC-4CFDAA04743E*
G04*
G04*
G04 #@! TF.FilePolarity,Positive*
G04*
G01*
G75*
%ADD19R,0.01860X0.02288*%
%ADD20R,0.02288X0.01860*%
%ADD21R,0.01968X0.02362*%
%ADD22R,0.02362X0.01968*%
%ADD23R,0.19685X0.03937*%
%ADD24C,0.03937*%
%ADD25R,0.03150X0.03150*%
G04:AMPARAMS|DCode=26|XSize=15.75mil|YSize=33.47mil|CornerRadius=1.97mil|HoleSize=0mil|Usage=FLASHONLY|Rotation=180.000|XOffset=0mil|YOffset=0mil|HoleType=Round|Shape=RoundedRectangle|*
%AMROUNDEDRECTD26*
21,1,0.01575,0.02953,0,0,180.0*
21,1,0.01181,0.03347,0,0,180.0*
1,1,0.00394,-0.00591,0.01476*
1,1,0.00394,0.00591,0.01476*
1,1,0.00394,0.00591,-0.01476*
1,1,0.00394,-0.00591,-0.01476*
%
%ADD26ROUNDEDRECTD26*%
%ADD27R,0.03150X0.05906*%
%ADD28R,0.05906X0.03150*%
%ADD29R,0.04331X0.04331*%
%ADD30R,0.02441X0.02362*%
%ADD31R,0.02423X0.02254*%
G04:AMPARAMS|DCode=32|XSize=11.81mil|YSize=31.5mil|CornerRadius=1.95mil|HoleSize=0mil|Usage=FLASHONLY|Rotation=90.000|XOffset=0mil|YOffset=0mil|HoleType=Round|Shape=RoundedRectangle|*
%AMROUNDEDRECTD32*
21,1,0.01181,0.02760,0,0,90.0*
21,1,0.00791,0.03150,0,0,90.0*
1,1,0.00390,0.01380,0.00396*
1,1,0.00390,0.01380,-0.00396*
1,1,0.00390,-0.01380,-0.00396*
1,1,0.00390,-0.01380,0.00396*
%
%ADD32ROUNDEDRECTD32*%
%ADD33R,0.03150X0.03543*%
%ADD34R,0.02559X0.03347*%
%ADD35R,0.02254X0.02423*%
%ADD36R,0.01788X0.01428*%
%ADD37R,0.03937X0.03543*%
%ADD38R,0.02362X0.02441*%
%ADD39R,0.11614X0.04016*%
G04:AMPARAMS|DCode=40|XSize=11.81mil|YSize=31.5mil|CornerRadius=1.95mil|HoleSize=0mil|Usage=FLASHONLY|Rotation=0.000|XOffset=0mil|YOffset=0mil|HoleType=Round|Shape=RoundedRectangle|*
%AMROUNDEDRECTD40*
21,1,0.01181,0.02760,0,0,0.0*
21,1,0.00791,0.03150,0,0,0.0*
1,1,0.00390,0.00396,-0.01380*
1,1,0.00390,-0.00396,-0.01380*
1,1,0.00390,-0.00396,0.01380*
1,1,0.00390,0.00396,0.01380*
%
%ADD40ROUNDEDRECTD40*%
G36*
X16111Y72171D02*
X16116Y72166D01*
X16120Y72160D01*
X16142Y72137D01*
X16163Y72113D01*
X16168Y72109D01*
X16173Y72103D01*
X17064Y71228D01*
X17081Y71213D01*
X17097Y71197D01*
X17110Y71187D01*
X17122Y71176D01*
X17140Y71163D01*
X17157Y71149D01*
X18173Y70422D01*
X18192Y70410D01*
X18211Y70397D01*
X18225Y70389D01*
X18238Y70380D01*
X18258Y70370D01*
X18278Y70359D01*
X19394Y69797D01*
X19414Y69788D01*
X19435Y69778D01*
X19450Y69773D01*
X19465Y69766D01*
X19486Y69759D01*
X19507Y69751D01*
X20696Y69369D01*
X20718Y69363D01*
X20740Y69357D01*
X20755Y69353D01*
X20771Y69349D01*
X20793Y69346D01*
X20815Y69341D01*
X22049Y69148D01*
X22072Y69145D01*
X22094Y69142D01*
X22110Y69141D01*
X22126Y69140D01*
X22149Y69139D01*
X22171Y69138D01*
X23420D01*
X23443Y69139D01*
X23465Y69140D01*
X23482Y69141D01*
X23498Y69142D01*
X23520Y69145D01*
X23542Y69148D01*
X24777Y69341D01*
X24799Y69346D01*
X24821Y69349D01*
X24836Y69353D01*
X24852Y69357D01*
X24874Y69363D01*
X24896Y69369D01*
X26085Y69751D01*
X26106Y69759D01*
X26127Y69766D01*
X26142Y69773D01*
X26157Y69778D01*
X26177Y69788D01*
X26198Y69797D01*
X27314Y70359D01*
X27334Y70370D01*
X27354Y70380D01*
X27367Y70389D01*
X27381Y70397D01*
X27400Y70410D01*
X27419Y70422D01*
X28434Y71149D01*
X28452Y71163D01*
X28470Y71176D01*
X28482Y71187D01*
X28495Y71197D01*
X28511Y71213D01*
X28528Y71228D01*
X29419Y72103D01*
X29424Y72109D01*
X29429Y72113D01*
X29450Y72137D01*
X29471Y72160D01*
X29476Y72166D01*
X29481Y72171D01*
X29636Y72364D01*
X36008Y72364D01*
Y64641D01*
X9584D01*
Y72364D01*
X15956D01*
X16111Y72171D01*
D02*
G37*
G36*
X23558Y80464D02*
X24033Y80267D01*
X24461Y79981D01*
X24825Y79617D01*
X25110Y79189D01*
X25307Y78714D01*
X25408Y78210D01*
Y77952D01*
Y77695D01*
X25307Y77191D01*
X25110Y76715D01*
X24825Y76288D01*
X24461Y75924D01*
X24033Y75638D01*
X23558Y75441D01*
X23053Y75341D01*
X22539D01*
X22034Y75441D01*
X21559Y75638D01*
X21131Y75924D01*
X20767Y76288D01*
X20482Y76715D01*
X20285Y77191D01*
X20184Y77695D01*
Y77952D01*
Y78210D01*
X20285Y78714D01*
X20482Y79189D01*
X20767Y79617D01*
X21131Y79981D01*
X21559Y80267D01*
X22034Y80464D01*
X22539Y80564D01*
X23053D01*
X23558Y80464D01*
D02*
G37*
G36*
X36008Y83541D02*
X29636D01*
X29481Y83734D01*
X29476Y83739D01*
X29471Y83745D01*
X29450Y83768D01*
X29429Y83791D01*
X29424Y83796D01*
X29419Y83802D01*
X28528Y84677D01*
X28511Y84692D01*
X28495Y84708D01*
X28482Y84718D01*
X28470Y84728D01*
X28452Y84742D01*
X28434Y84756D01*
X27419Y85483D01*
X27400Y85495D01*
X27381Y85508D01*
X27367Y85516D01*
X27354Y85525D01*
X27334Y85535D01*
X27314Y85546D01*
X26198Y86107D01*
X26177Y86116D01*
X26157Y86126D01*
X26142Y86132D01*
X26127Y86139D01*
X26106Y86146D01*
X26085Y86154D01*
X24896Y86536D01*
X24874Y86541D01*
X24852Y86548D01*
X24836Y86551D01*
X24821Y86555D01*
X24799Y86559D01*
X24777Y86564D01*
X23542Y86757D01*
X23520Y86759D01*
X23498Y86763D01*
X23482Y86764D01*
X23465Y86765D01*
X23443Y86765D01*
X23420Y86766D01*
X22171D01*
X22149Y86765D01*
X22126Y86765D01*
X22110Y86764D01*
X22094Y86763D01*
X22072Y86759D01*
X22049Y86757D01*
X20815Y86564D01*
X20793Y86559D01*
X20771Y86555D01*
X20755Y86551D01*
X20740Y86548D01*
X20718Y86541D01*
X20696Y86536D01*
X19507Y86154D01*
X19486Y86146D01*
X19465Y86139D01*
X19450Y86132D01*
X19435Y86126D01*
X19414Y86116D01*
X19394Y86107D01*
X18278Y85546D01*
X18258Y85535D01*
X18238Y85525D01*
X18225Y85516D01*
X18211Y85508D01*
X18192Y85495D01*
X18173Y85483D01*
X17157Y84756D01*
X17140Y84742D01*
X17122Y84728D01*
X17110Y84718D01*
X17097Y84708D01*
X17081Y84692D01*
X17064Y84677D01*
X16173Y83802D01*
X16168Y83796D01*
X16163Y83791D01*
X16142Y83768D01*
X16120Y83745D01*
X16116Y83739D01*
X16111Y83734D01*
X15956Y83541D01*
X9584D01*
Y91264D01*
X36008D01*
Y83541D01*
D02*
G37*
D19*
X208132Y14520D02*
D03*
Y11642D02*
D03*
X239900Y79220D02*
D03*
Y76341D02*
D03*
X192400Y14520D02*
D03*
Y11642D02*
D03*
X211600Y52939D02*
D03*
Y50061D02*
D03*
X219800D02*
D03*
Y52939D02*
D03*
D20*
X63439Y18180D02*
D03*
X60561D02*
D03*
X70439Y46000D02*
D03*
X67561D02*
D03*
D21*
X84969Y48200D02*
D03*
X81032D02*
D03*
X81132Y69300D02*
D03*
X85069D02*
D03*
X63468Y46000D02*
D03*
X59531D02*
D03*
D22*
X212400Y68568D02*
D03*
Y64631D02*
D03*
X220100Y68568D02*
D03*
Y64631D02*
D03*
X133500Y100531D02*
D03*
Y104469D02*
D03*
D23*
X22795Y66472D02*
D03*
X21795Y88953D02*
D03*
D24*
X22796Y77952D02*
D03*
X146000Y101500D02*
D03*
X140500D02*
D03*
X116500D02*
D03*
X111000D02*
D03*
X105500D02*
D03*
X174500Y15000D02*
D03*
X169000D02*
D03*
X163500D02*
D03*
D25*
X249100Y84548D02*
D03*
Y78052D02*
D03*
X200168Y19848D02*
D03*
Y13352D02*
D03*
X215900D02*
D03*
Y19848D02*
D03*
D26*
X58441Y68929D02*
D03*
X63559D02*
D03*
Y60071D02*
D03*
X61000D02*
D03*
X58441D02*
D03*
D27*
X151154Y93039D02*
D03*
X146823D02*
D03*
X142492D02*
D03*
X138161D02*
D03*
X133831D02*
D03*
X129500D02*
D03*
X125169D02*
D03*
X112177D02*
D03*
X107846D02*
D03*
X103516D02*
D03*
X116508D02*
D03*
X120839D02*
D03*
X99185D02*
D03*
Y14693D02*
D03*
X103516D02*
D03*
X107846D02*
D03*
X112177D02*
D03*
X116508D02*
D03*
X120839D02*
D03*
X125169D02*
D03*
X129500D02*
D03*
X133831D02*
D03*
X138161D02*
D03*
X142492D02*
D03*
X146823D02*
D03*
X151154D02*
D03*
D28*
X95839Y82016D02*
D03*
Y77685D02*
D03*
Y73354D02*
D03*
Y69024D02*
D03*
Y64693D02*
D03*
Y60362D02*
D03*
Y56032D02*
D03*
Y51701D02*
D03*
Y47370D02*
D03*
Y43039D02*
D03*
Y38709D02*
D03*
Y34378D02*
D03*
Y30047D02*
D03*
Y25717D02*
D03*
X154500D02*
D03*
Y30047D02*
D03*
Y34378D02*
D03*
Y38709D02*
D03*
Y43039D02*
D03*
Y47370D02*
D03*
Y51701D02*
D03*
Y56032D02*
D03*
Y60362D02*
D03*
Y64693D02*
D03*
Y69024D02*
D03*
Y73354D02*
D03*
Y77685D02*
D03*
Y82016D02*
D03*
D29*
X104500Y24929D02*
D03*
Y33197D02*
D03*
Y41465D02*
D03*
Y49732D02*
D03*
Y58000D02*
D03*
Y66268D02*
D03*
Y74535D02*
D03*
X104500Y82803D02*
D03*
X112768Y24929D02*
D03*
Y33197D02*
D03*
Y41465D02*
D03*
Y49732D02*
D03*
Y58000D02*
D03*
Y66268D02*
D03*
Y74535D02*
D03*
X112768Y82803D02*
D03*
X121035Y24929D02*
D03*
Y33197D02*
D03*
Y41465D02*
D03*
Y49732D02*
D03*
Y58000D02*
D03*
Y66268D02*
D03*
Y74535D02*
D03*
X121035Y82803D02*
D03*
X129303Y24929D02*
D03*
Y33197D02*
D03*
Y41465D02*
D03*
Y49732D02*
D03*
Y58000D02*
D03*
Y66268D02*
D03*
Y74535D02*
D03*
X129303Y82803D02*
D03*
X137571Y24929D02*
D03*
Y33197D02*
D03*
Y41465D02*
D03*
Y49732D02*
D03*
Y58000D02*
D03*
Y66268D02*
D03*
Y74535D02*
D03*
X137571Y82803D02*
D03*
X145838Y24929D02*
D03*
Y33197D02*
D03*
Y41465D02*
D03*
Y49732D02*
D03*
Y58000D02*
D03*
Y66268D02*
D03*
Y74535D02*
D03*
X145838Y82803D02*
D03*
D30*
X127500Y104311D02*
D03*
Y100689D02*
D03*
D31*
X76163Y69089D02*
D03*
X72789D02*
D03*
X210490Y43400D02*
D03*
X213864D02*
D03*
X78187Y77600D02*
D03*
X74813D02*
D03*
X60687Y53500D02*
D03*
X57313D02*
D03*
D32*
X84299Y55347D02*
D03*
Y57316D02*
D03*
Y59284D02*
D03*
Y61253D02*
D03*
X71701Y55347D02*
D03*
Y57316D02*
D03*
Y59284D02*
D03*
Y61253D02*
D03*
D33*
X55760Y26563D02*
D03*
X63240D02*
D03*
X59500Y34437D02*
D03*
D34*
X43000Y72039D02*
D03*
Y76961D02*
D03*
D35*
X51500Y73813D02*
D03*
Y77187D02*
D03*
D36*
X51198Y65000D02*
D03*
X48802D02*
D03*
D37*
X51500Y45850D02*
D03*
Y52150D02*
D03*
D38*
X161689Y46000D02*
D03*
X165311D02*
D03*
Y51500D02*
D03*
X161689D02*
D03*
X165311Y60000D02*
D03*
X161689D02*
D03*
Y65500D02*
D03*
X165311D02*
D03*
D39*
X249390Y32598D02*
D03*
Y40472D02*
D03*
Y48346D02*
D03*
Y56221D02*
D03*
X231476Y32598D02*
D03*
Y40472D02*
D03*
Y48346D02*
D03*
Y56221D02*
D03*
D40*
X197647Y43401D02*
D03*
X199616D02*
D03*
X201584D02*
D03*
X203553D02*
D03*
X197647Y55999D02*
D03*
X199616D02*
D03*
X201584D02*
D03*
X203553D02*
D03*
M02*
